(kicad_pcb
	(version 20260206)
	(generator "pcbnew")
	(generator_version "10.0")
	(general
		(thickness 1.6)
		(legacy_teardrops no)
	)
	(paper "A4")
	(title_block
		(title "03242023_DA0F0TMBIJ0_F0T_Motherboard_J_brd_V01_OCP.brd")
		(comment 1 "Grand Teton / footprints 1638-1644 of 6105")
	)
	(layers
		(0 "F.Cu" signal "TOP")
		(4 "In1.Cu" signal "GND")
		(6 "In2.Cu" signal "IN1")
		(8 "In3.Cu" signal "GND1")
		(10 "In4.Cu" signal "IN2")
		(12 "In5.Cu" signal "GND2")
		(14 "In6.Cu" signal "IN3")
		(16 "In7.Cu" signal "GND3")
		(18 "In8.Cu" signal "VCC")
		(20 "In9.Cu" signal "VCC1")
		(22 "In10.Cu" signal "GND4")
		(24 "In11.Cu" signal "IN4")
		(26 "In12.Cu" signal "GND5")
		(28 "In13.Cu" signal "IN5")
		(30 "In14.Cu" signal "GND6")
		(32 "In15.Cu" signal "IN6")
		(34 "In16.Cu" signal "GND7")
		(2 "B.Cu" signal "BOTTOM")
		(9 "F.Adhes" user "F.Adhesive")
		(11 "B.Adhes" user "B.Adhesive")
		(13 "F.Paste" user "Package Geometry/Pastemask Top")
		(15 "B.Paste" user "Package Geometry/Pastemask Bottom")
		(5 "F.SilkS" user "Ref Des/Silkscreen Top")
		(7 "B.SilkS" user "Ref Des/Silkscreen Bottom")
		(1 "F.Mask" user "Board Geometry/Soldermask Top")
		(3 "B.Mask" user "Board Geometry/Soldermask Bottom")
		(17 "Dwgs.User" user "User.Drawings")
		(19 "Cmts.User" user "User.Comments")
		(21 "Eco1.User" user "User.Eco1")
		(23 "Eco2.User" user "User.Eco2")
		(25 "Edge.Cuts" user "Board Geometry/Outline")
		(27 "Margin" user)
		(31 "F.CrtYd" user "Package Geometry/Place Bound Top")
		(29 "B.CrtYd" user "Package Geometry/Place Bound Bottom")
		(35 "F.Fab" user "Ref Des/Assembly Top")
		(33 "B.Fab" user "Ref Des/Assembly Bottom")
	)
	(footprint ""
		(layer "F.Cu")
		(at 393.814046 -389.123936)
		(property "Reference" "ME17"
			(at 0 0 0)
			(layer "F.SilkS")
			(hide yes)
			(effects
				(font
					(size 1.27 1.27)
				)
			)
		)
		(property "Value" ""
			(at 0 0 0)
			(layer "F.Fab")
			(effects
				(font
					(size 1.27 1.27)
				)
			)
		)
		(duplicate_pad_numbers_are_jumpers no)
	)
	(footprint ""
		(layer "F.Cu")
		(at 111.332772 -128.075182)
		(property "Reference" "R3536"
			(at 0 0 0)
			(layer "F.SilkS")
			(hide yes)
			(effects
				(font
					(size 1.27 1.27)
				)
			)
		)
		(property "Value" ""
			(at 0 0 0)
			(layer "F.Fab")
			(effects
				(font
					(size 1.27 1.27)
				)
			)
		)
		(duplicate_pad_numbers_are_jumpers no)
		(fp_line
			(start -0.7874 -0.4064)
			(end 0.7874 -0.4064)
			(stroke
				(width 0.1524)
				(type default)
			)
			(layer "F.SilkS")
		)
		(fp_line
			(start -0.7874 0.4064)
			(end -0.7874 -0.4064)
			(stroke
				(width 0.1524)
				(type default)
			)
			(layer "F.SilkS")
		)
		(fp_line
			(start 0.7874 -0.4064)
			(end 0.7874 0.4064)
			(stroke
				(width 0.1524)
				(type default)
			)
			(layer "F.SilkS")
		)
		(fp_line
			(start 0.7874 0.4064)
			(end -0.7874 0.4064)
			(stroke
				(width 0.1524)
				(type default)
			)
			(layer "F.SilkS")
		)
		(fp_line
			(start -0.67945 -0.305054)
			(end -0.12065 -0.305054)
			(stroke
				(width 0.1)
				(type default)
			)
			(layer "F.Fab")
		)
		(fp_line
			(start -0.67945 0.3048)
			(end -0.67945 -0.305054)
			(stroke
				(width 0.1)
				(type default)
			)
			(layer "F.Fab")
		)
		(fp_line
			(start -0.12065 -0.305054)
			(end -0.12065 -0.2794)
			(stroke
				(width 0.1)
				(type default)
			)
			(layer "F.Fab")
		)
		(fp_line
			(start -0.12065 -0.2794)
			(end 0.12065 -0.2794)
			(stroke
				(width 0.1)
				(type default)
			)
			(layer "F.Fab")
		)
		(fp_line
			(start -0.12065 0.2794)
			(end -0.12065 0.3048)
			(stroke
				(width 0.1)
				(type default)
			)
			(layer "F.Fab")
		)
		(fp_line
			(start -0.12065 0.3048)
			(end -0.67945 0.3048)
			(stroke
				(width 0.1)
				(type default)
			)
			(layer "F.Fab")
		)
		(fp_line
			(start 0.120396 0.2794)
			(end -0.12065 0.2794)
			(stroke
				(width 0.1)
				(type default)
			)
			(layer "F.Fab")
		)
		(fp_line
			(start 0.120396 0.3048)
			(end 0.120396 0.2794)
			(stroke
				(width 0.1)
				(type default)
			)
			(layer "F.Fab")
		)
		(fp_line
			(start 0.12065 -0.3048)
			(end 0.67945 -0.3048)
			(stroke
				(width 0.1)
				(type default)
			)
			(layer "F.Fab")
		)
		(fp_line
			(start 0.12065 -0.2794)
			(end 0.12065 -0.3048)
			(stroke
				(width 0.1)
				(type default)
			)
			(layer "F.Fab")
		)
		(fp_line
			(start 0.67945 -0.3048)
			(end 0.67945 0.3048)
			(stroke
				(width 0.1)
				(type default)
			)
			(layer "F.Fab")
		)
		(fp_line
			(start 0.67945 0.3048)
			(end 0.120396 0.3048)
			(stroke
				(width 0.1)
				(type default)
			)
			(layer "F.Fab")
		)
		(pad "1" smd circle
			(at -0.40005 0)
			(size 0 0)
			(layers "F.Cu" "F.Mask" "F.Paste")
			(net "P3V3_AUX")
		)
		(pad "2" smd circle
			(at 0.40005 0)
			(size 0 0)
			(layers "F.Cu" "F.Mask" "F.Paste")
			(net "SMB_SENSOR_E1S_3V3AUX_SDA")
		)
	)
	(footprint ""
		(layer "F.Cu")
		(at 239.152684 -53.821838 180)
		(property "Reference" "C1993"
			(at 0 0 180)
			(layer "F.SilkS")
			(hide yes)
			(effects
				(font
					(size 1.27 1.27)
				)
			)
		)
		(property "Value" ""
			(at 0 0 180)
			(layer "F.Fab")
			(effects
				(font
					(size 1.27 1.27)
				)
			)
		)
		(duplicate_pad_numbers_are_jumpers no)
		(fp_line
			(start 0.299974 0.150114)
			(end -0.299974 0.150114)
			(stroke
				(width 0.1)
				(type default)
			)
			(layer "F.Fab")
		)
		(fp_line
			(start 0.299974 -0.150114)
			(end 0.299974 0.150114)
			(stroke
				(width 0.1)
				(type default)
			)
			(layer "F.Fab")
		)
		(fp_line
			(start -0.299974 0.150114)
			(end -0.299974 -0.150114)
			(stroke
				(width 0.1)
				(type default)
			)
			(layer "F.Fab")
		)
		(fp_line
			(start -0.299974 -0.150114)
			(end 0.299974 -0.150114)
			(stroke
				(width 0.1)
				(type default)
			)
			(layer "F.Fab")
		)
		(pad "1" smd rect
			(at -0.2667 0 180)
			(size 0.3048 0.381)
			(layers "F.Cu" "F.Mask" "F.Paste")
			(net "P3E_PCH_E1S_TX_DP<1>")
		)
		(pad "2" smd rect
			(at 0.2667 0 180)
			(size 0.3048 0.381)
			(layers "F.Cu" "F.Mask" "F.Paste")
			(net "P3E_PCH_E1S_TX_C_DP<1>")
		)
		(zone
			(layer "In1.Cu")
			(hatch none 0.5)
			(connect_pads
				(clearance 0)
			)
			(min_thickness 0.25)
			(keepout
				(tracks not_allowed)
				(vias allowed)
				(pads allowed)
				(copperpour not_allowed)
				(footprints allowed)
			)
			(placement
				(enabled no)
				(sheetname "")
			)
			(fill
				(thermal_gap 0.5)
				(thermal_bridge_width 0.5)
				(island_removal_mode 0)
			)
			(polygon
				(pts
					(arc
						(start 239.012984 -54.062122)
						(mid 239.066866 -54.039804)
						(end 239.089184 -53.985922)
					)
					(arc
						(start 239.089184 -53.655722)
						(mid 239.066866 -53.60184)
						(end 239.012984 -53.579522)
					)
					(arc
						(start 238.758984 -53.579522)
						(mid 238.705102 -53.60184)
						(end 238.682784 -53.655722)
					)
					(arc
						(start 238.682784 -53.985922)
						(mid 238.705102 -54.039804)
						(end 238.758984 -54.062122)
					)
				)
			)
		)
		(zone
			(layer "In1.Cu")
			(hatch none 0.5)
			(connect_pads
				(clearance 0)
			)
			(min_thickness 0.25)
			(keepout
				(tracks not_allowed)
				(vias allowed)
				(pads allowed)
				(copperpour not_allowed)
				(footprints allowed)
			)
			(placement
				(enabled no)
				(sheetname "")
			)
			(fill
				(thermal_gap 0.5)
				(thermal_bridge_width 0.5)
				(island_removal_mode 0)
			)
			(polygon
				(pts
					(arc
						(start 239.546384 -54.062122)
						(mid 239.600266 -54.039804)
						(end 239.622584 -53.985922)
					)
					(arc
						(start 239.622584 -53.655722)
						(mid 239.600266 -53.60184)
						(end 239.546384 -53.579522)
					)
					(arc
						(start 239.292384 -53.579522)
						(mid 239.238502 -53.60184)
						(end 239.216184 -53.655722)
					)
					(arc
						(start 239.216184 -53.985922)
						(mid 239.238502 -54.039804)
						(end 239.292384 -54.062122)
					)
				)
			)
		)
	)
	(footprint ""
		(layer "F.Cu")
		(at 53.87848 -433.898548 -90)
		(property "Reference" "R3227"
			(at 0 0 270)
			(layer "F.SilkS")
			(hide yes)
			(effects
				(font
					(size 1.27 1.27)
				)
			)
		)
		(property "Value" ""
			(at 0 0 270)
			(layer "F.Fab")
			(effects
				(font
					(size 1.27 1.27)
				)
			)
		)
		(duplicate_pad_numbers_are_jumpers no)
		(fp_line
			(start -0.7874 0.4064)
			(end -0.7874 -0.4064)
			(stroke
				(width 0.1524)
				(type default)
			)
			(layer "F.SilkS")
		)
		(fp_line
			(start 0.7874 0.4064)
			(end -0.7874 0.4064)
			(stroke
				(width 0.1524)
				(type default)
			)
			(layer "F.SilkS")
		)
		(fp_line
			(start -0.7874 -0.4064)
			(end 0.7874 -0.4064)
			(stroke
				(width 0.1524)
				(type default)
			)
			(layer "F.SilkS")
		)
		(fp_line
			(start 0.7874 -0.4064)
			(end 0.7874 0.4064)
			(stroke
				(width 0.1524)
				(type default)
			)
			(layer "F.SilkS")
		)
		(fp_line
			(start -0.67945 0.3048)
			(end -0.67945 -0.305054)
			(stroke
				(width 0.1)
				(type default)
			)
			(layer "F.Fab")
		)
		(fp_line
			(start -0.12065 0.3048)
			(end -0.67945 0.3048)
			(stroke
				(width 0.1)
				(type default)
			)
			(layer "F.Fab")
		)
		(fp_line
			(start 0.120396 0.3048)
			(end 0.120396 0.2794)
			(stroke
				(width 0.1)
				(type default)
			)
			(layer "F.Fab")
		)
		(fp_line
			(start 0.67945 0.3048)
			(end 0.120396 0.3048)
			(stroke
				(width 0.1)
				(type default)
			)
			(layer "F.Fab")
		)
		(fp_line
			(start -0.12065 0.2794)
			(end -0.12065 0.3048)
			(stroke
				(width 0.1)
				(type default)
			)
			(layer "F.Fab")
		)
		(fp_line
			(start 0.120396 0.2794)
			(end -0.12065 0.2794)
			(stroke
				(width 0.1)
				(type default)
			)
			(layer "F.Fab")
		)
		(fp_line
			(start -0.12065 -0.2794)
			(end 0.12065 -0.2794)
			(stroke
				(width 0.1)
				(type default)
			)
			(layer "F.Fab")
		)
		(fp_line
			(start 0.12065 -0.2794)
			(end 0.12065 -0.3048)
			(stroke
				(width 0.1)
				(type default)
			)
			(layer "F.Fab")
		)
		(fp_line
			(start 0.12065 -0.3048)
			(end 0.67945 -0.3048)
			(stroke
				(width 0.1)
				(type default)
			)
			(layer "F.Fab")
		)
		(fp_line
			(start 0.67945 -0.3048)
			(end 0.67945 0.3048)
			(stroke
				(width 0.1)
				(type default)
			)
			(layer "F.Fab")
		)
		(fp_line
			(start -0.67945 -0.305054)
			(end -0.12065 -0.305054)
			(stroke
				(width 0.1)
				(type default)
			)
			(layer "F.Fab")
		)
		(fp_line
			(start -0.12065 -0.305054)
			(end -0.12065 -0.2794)
			(stroke
				(width 0.1)
				(type default)
			)
			(layer "F.Fab")
		)
		(pad "1" smd circle
			(at -0.40005 0 270)
			(size 0 0)
			(layers "F.Cu" "F.Mask" "F.Paste")
			(net "SMB_1_BMC_GPU_SDA")
		)
		(pad "2" smd circle
			(at 0.40005 0 270)
			(size 0 0)
			(layers "F.Cu" "F.Mask" "F.Paste")
			(net "P3V3_AUX")
		)
	)
	(footprint ""
		(layer "F.Cu")
		(at 385.716272 -66.704464 180)
		(property "Reference" "C547"
			(at 0 0 180)
			(layer "F.SilkS")
			(hide yes)
			(effects
				(font
					(size 1.27 1.27)
				)
			)
		)
		(property "Value" ""
			(at 0 0 180)
			(layer "F.Fab")
			(effects
				(font
					(size 1.27 1.27)
				)
			)
		)
		(duplicate_pad_numbers_are_jumpers no)
		(fp_line
			(start 0.7874 0.4064)
			(end -0.7874 0.4064)
			(stroke
				(width 0.1524)
				(type default)
			)
			(layer "F.SilkS")
		)
		(fp_line
			(start 0.7874 -0.4064)
			(end 0.7874 0.4064)
			(stroke
				(width 0.1524)
				(type default)
			)
			(layer "F.SilkS")
		)
		(fp_line
			(start -0.7874 0.4064)
			(end -0.7874 -0.4064)
			(stroke
				(width 0.1524)
				(type default)
			)
			(layer "F.SilkS")
		)
		(fp_line
			(start -0.7874 -0.4064)
			(end 0.7874 -0.4064)
			(stroke
				(width 0.1524)
				(type default)
			)
			(layer "F.SilkS")
		)
		(fp_line
			(start 0.67945 0.3048)
			(end 0.120396 0.3048)
			(stroke
				(width 0.1)
				(type default)
			)
			(layer "F.Fab")
		)
		(fp_line
			(start 0.67945 -0.3048)
			(end 0.67945 0.3048)
			(stroke
				(width 0.1)
				(type default)
			)
			(layer "F.Fab")
		)
		(fp_line
			(start 0.12065 -0.2794)
			(end 0.12065 -0.3048)
			(stroke
				(width 0.1)
				(type default)
			)
			(layer "F.Fab")
		)
		(fp_line
			(start 0.12065 -0.3048)
			(end 0.67945 -0.3048)
			(stroke
				(width 0.1)
				(type default)
			)
			(layer "F.Fab")
		)
		(fp_line
			(start 0.120396 0.3048)
			(end 0.120396 0.2794)
			(stroke
				(width 0.1)
				(type default)
			)
			(layer "F.Fab")
		)
		(fp_line
			(start 0.120396 0.2794)
			(end -0.12065 0.2794)
			(stroke
				(width 0.1)
				(type default)
			)
			(layer "F.Fab")
		)
		(fp_line
			(start -0.12065 0.3048)
			(end -0.67945 0.3048)
			(stroke
				(width 0.1)
				(type default)
			)
			(layer "F.Fab")
		)
		(fp_line
			(start -0.12065 0.2794)
			(end -0.12065 0.3048)
			(stroke
				(width 0.1)
				(type default)
			)
			(layer "F.Fab")
		)
		(fp_line
			(start -0.12065 -0.2794)
			(end 0.12065 -0.2794)
			(stroke
				(width 0.1)
				(type default)
			)
			(layer "F.Fab")
		)
		(fp_line
			(start -0.12065 -0.305054)
			(end -0.12065 -0.2794)
			(stroke
				(width 0.1)
				(type default)
			)
			(layer "F.Fab")
		)
		(fp_line
			(start -0.67945 0.3048)
			(end -0.67945 -0.305054)
			(stroke
				(width 0.1)
				(type default)
			)
			(layer "F.Fab")
		)
		(fp_line
			(start -0.67945 -0.305054)
			(end -0.12065 -0.305054)
			(stroke
				(width 0.1)
				(type default)
			)
			(layer "F.Fab")
		)
		(pad "1" smd circle
			(at -0.40005 0 180)
			(size 0 0)
			(layers "F.Cu" "F.Mask" "F.Paste")
			(net "P1V05_PCH_AUX")
		)
		(pad "2" smd circle
			(at 0.40005 0 180)
			(size 0 0)
			(layers "F.Cu" "F.Mask" "F.Paste")
			(net "GND")
		)
	)
	(footprint ""
		(layer "F.Cu")
		(at 9.58088 -61.051948)
		(property "Reference" "R3058"
			(at 0 0 0)
			(layer "F.SilkS")
			(hide yes)
			(effects
				(font
					(size 1.27 1.27)
				)
			)
		)
		(property "Value" ""
			(at 0 0 0)
			(layer "F.Fab")
			(effects
				(font
					(size 1.27 1.27)
				)
			)
		)
		(duplicate_pad_numbers_are_jumpers no)
		(fp_line
			(start -0.7874 -0.4064)
			(end 0.7874 -0.4064)
			(stroke
				(width 0.1524)
				(type default)
			)
			(layer "F.SilkS")
		)
		(fp_line
			(start -0.7874 0.4064)
			(end -0.7874 -0.4064)
			(stroke
				(width 0.1524)
				(type default)
			)
			(layer "F.SilkS")
		)
		(fp_line
			(start 0.7874 -0.4064)
			(end 0.7874 0.4064)
			(stroke
				(width 0.1524)
				(type default)
			)
			(layer "F.SilkS")
		)
		(fp_line
			(start 0.7874 0.4064)
			(end -0.7874 0.4064)
			(stroke
				(width 0.1524)
				(type default)
			)
			(layer "F.SilkS")
		)
		(fp_line
			(start -0.67945 -0.305054)
			(end -0.12065 -0.305054)
			(stroke
				(width 0.1)
				(type default)
			)
			(layer "F.Fab")
		)
		(fp_line
			(start -0.67945 0.3048)
			(end -0.67945 -0.305054)
			(stroke
				(width 0.1)
				(type default)
			)
			(layer "F.Fab")
		)
		(fp_line
			(start -0.12065 -0.305054)
			(end -0.12065 -0.2794)
			(stroke
				(width 0.1)
				(type default)
			)
			(layer "F.Fab")
		)
		(fp_line
			(start -0.12065 -0.2794)
			(end 0.12065 -0.2794)
			(stroke
				(width 0.1)
				(type default)
			)
			(layer "F.Fab")
		)
		(fp_line
			(start -0.12065 0.2794)
			(end -0.12065 0.3048)
			(stroke
				(width 0.1)
				(type default)
			)
			(layer "F.Fab")
		)
		(fp_line
			(start -0.12065 0.3048)
			(end -0.67945 0.3048)
			(stroke
				(width 0.1)
				(type default)
			)
			(layer "F.Fab")
		)
		(fp_line
			(start 0.120396 0.2794)
			(end -0.12065 0.2794)
			(stroke
				(width 0.1)
				(type default)
			)
			(layer "F.Fab")
		)
		(fp_line
			(start 0.120396 0.3048)
			(end 0.120396 0.2794)
			(stroke
				(width 0.1)
				(type default)
			)
			(layer "F.Fab")
		)
		(fp_line
			(start 0.12065 -0.3048)
			(end 0.67945 -0.3048)
			(stroke
				(width 0.1)
				(type default)
			)
			(layer "F.Fab")
		)
		(fp_line
			(start 0.12065 -0.2794)
			(end 0.12065 -0.3048)
			(stroke
				(width 0.1)
				(type default)
			)
			(layer "F.Fab")
		)
		(fp_line
			(start 0.67945 -0.3048)
			(end 0.67945 0.3048)
			(stroke
				(width 0.1)
				(type default)
			)
			(layer "F.Fab")
		)
		(fp_line
			(start 0.67945 0.3048)
			(end 0.120396 0.3048)
			(stroke
				(width 0.1)
				(type default)
			)
			(layer "F.Fab")
		)
		(pad "1" smd circle
			(at -0.40005 0)
			(size 0 0)
			(layers "F.Cu" "F.Mask" "F.Paste")
			(net "SMB_SML0_3V3AUX_SCL")
		)
		(pad "2" smd circle
			(at 0.40005 0)
			(size 0 0)
			(layers "F.Cu" "F.Mask" "F.Paste")
			(net "SMB_SML0_ME_SCL")
		)
	)
	(footprint ""
		(layer "F.Cu")
		(at 20.60956 -72.710548)
		(property "Reference" "R3134"
			(at 0 0 0)
			(layer "F.SilkS")
			(hide yes)
			(effects
				(font
					(size 1.27 1.27)
				)
			)
		)
		(property "Value" ""
			(at 0 0 0)
			(layer "F.Fab")
			(effects
				(font
					(size 1.27 1.27)
				)
			)
		)
		(duplicate_pad_numbers_are_jumpers no)
		(fp_line
			(start -0.7874 -0.4064)
			(end 0.7874 -0.4064)
			(stroke
				(width 0.1524)
				(type default)
			)
			(layer "F.SilkS")
		)
		(fp_line
			(start -0.7874 0.4064)
			(end -0.7874 -0.4064)
			(stroke
				(width 0.1524)
				(type default)
			)
			(layer "F.SilkS")
		)
		(fp_line
			(start 0.7874 -0.4064)
			(end 0.7874 0.4064)
			(stroke
				(width 0.1524)
				(type default)
			)
			(layer "F.SilkS")
		)
		(fp_line
			(start 0.7874 0.4064)
			(end -0.7874 0.4064)
			(stroke
				(width 0.1524)
				(type default)
			)
			(layer "F.SilkS")
		)
		(fp_line
			(start -0.67945 -0.305054)
			(end -0.12065 -0.305054)
			(stroke
				(width 0.1)
				(type default)
			)
			(layer "F.Fab")
		)
		(fp_line
			(start -0.67945 0.3048)
			(end -0.67945 -0.305054)
			(stroke
				(width 0.1)
				(type default)
			)
			(layer "F.Fab")
		)
		(fp_line
			(start -0.12065 -0.305054)
			(end -0.12065 -0.2794)
			(stroke
				(width 0.1)
				(type default)
			)
			(layer "F.Fab")
		)
		(fp_line
			(start -0.12065 -0.2794)
			(end 0.12065 -0.2794)
			(stroke
				(width 0.1)
				(type default)
			)
			(layer "F.Fab")
		)
		(fp_line
			(start -0.12065 0.2794)
			(end -0.12065 0.3048)
			(stroke
				(width 0.1)
				(type default)
			)
			(layer "F.Fab")
		)
		(fp_line
			(start -0.12065 0.3048)
			(end -0.67945 0.3048)
			(stroke
				(width 0.1)
				(type default)
			)
			(layer "F.Fab")
		)
		(fp_line
			(start 0.120396 0.2794)
			(end -0.12065 0.2794)
			(stroke
				(width 0.1)
				(type default)
			)
			(layer "F.Fab")
		)
		(fp_line
			(start 0.120396 0.3048)
			(end 0.120396 0.2794)
			(stroke
				(width 0.1)
				(type default)
			)
			(layer "F.Fab")
		)
		(fp_line
			(start 0.12065 -0.3048)
			(end 0.67945 -0.3048)
			(stroke
				(width 0.1)
				(type default)
			)
			(layer "F.Fab")
		)
		(fp_line
			(start 0.12065 -0.2794)
			(end 0.12065 -0.3048)
			(stroke
				(width 0.1)
				(type default)
			)
			(layer "F.Fab")
		)
		(fp_line
			(start 0.67945 -0.3048)
			(end 0.67945 0.3048)
			(stroke
				(width 0.1)
				(type default)
			)
			(layer "F.Fab")
		)
		(fp_line
			(start 0.67945 0.3048)
			(end 0.120396 0.3048)
			(stroke
				(width 0.1)
				(type default)
			)
			(layer "F.Fab")
		)
		(pad "1" smd circle
			(at -0.40005 0)
			(size 0 0)
			(layers "F.Cu" "F.Mask" "F.Paste")
			(net "P3V3_AUX")
		)
		(pad "2" smd circle
			(at 0.40005 0)
			(size 0 0)
			(layers "F.Cu" "F.Mask" "F.Paste")
			(net "OCP_V3_2_PRSNT2_R_N")
		)
	)
)
